# SCM (Grand Teton) — schematic netlist excerpt (pin names and nets, part order shuffled) for the footprints in the layout excerpt that follows; sources: Cadence DE-HDL packaged netlist, KiCad conversion of 12092022_DA0F0TMDCD0_F0T_Management_Board_D_brd_V3_OCP.brd

C286  Q_CAP  0.01UF 50V 10% EMPTY  pkg C0402  page 41 : A = PVCCA_AUX_PLD ; B = GND
C6  Q_CAP  0.1UF 25V 10% X7R  pkg 0402  page 20 : A = P2V5_AUX ; B = GND

(kicad_pcb
	(version 20260206)
	(generator "pcbnew")
	(generator_version "10.0")
	(general
		(thickness 1.6)
		(legacy_teardrops no)
	)
	(paper "A4")
	(title_block
		(title "12092022_DA0F0TMDCD0_F0T_Management_Board_D_brd_V3_OCP.brd")
		(comment 1 "Grand Teton / footprints 1183-1184 of 1440")
	)
	(layers
		(0 "F.Cu" signal "TOP")
		(4 "In1.Cu" signal "GND")
		(6 "In2.Cu" signal "IN1")
		(8 "In3.Cu" signal "GND1")
		(10 "In4.Cu" signal "IN2")
		(12 "In5.Cu" signal "VCC")
		(14 "In6.Cu" signal "VCC1")
		(16 "In7.Cu" signal "IN3")
		(18 "In8.Cu" signal "GND2")
		(20 "In9.Cu" signal "IN4")
		(22 "In10.Cu" signal "GND3")
		(2 "B.Cu" signal "BOTTOM")
		(9 "F.Adhes" user "F.Adhesive")
		(11 "B.Adhes" user "B.Adhesive")
		(13 "F.Paste" user "Package Geometry/Pastemask Top")
		(15 "B.Paste" user "Package Geometry/Pastemask Bottom")
		(5 "F.SilkS" user "Ref Des/Silkscreen Top")
		(7 "B.SilkS" user "Ref Des/Silkscreen Bottom")
		(1 "F.Mask" user "Board Geometry/Soldermask Top")
		(3 "B.Mask" user "Board Geometry/Soldermask Bottom")
		(17 "Dwgs.User" user "User.Drawings")
		(19 "Cmts.User" user "User.Comments")
		(21 "Eco1.User" user "User.Eco1")
		(23 "Eco2.User" user "User.Eco2")
		(25 "Edge.Cuts" user "Board Geometry/Outline")
		(27 "Margin" user)
		(31 "F.CrtYd" user "Package Geometry/Place Bound Top")
		(29 "B.CrtYd" user "Package Geometry/Place Bound Bottom")
		(35 "F.Fab" user "Ref Des/Assembly Top")
		(33 "B.Fab" user "Ref Des/Assembly Bottom")
	)
	(footprint ""
		(layer "B.Cu")
		(at 26.543 -99.695 45)
		(property "Reference" "C286"
			(at 0 0 45)
			(layer "B.SilkS")
			(hide yes)
			(effects
				(font
					(size 1.27 1.27)
				)
				(justify mirror)
			)
		)
		(property "Value" ""
			(at 0 0 45)
			(layer "B.Fab")
			(effects
				(font
					(size 1.27 1.27)
				)
				(justify mirror)
			)
		)
		(duplicate_pad_numbers_are_jumpers no)
		(fp_line
			(start -0.787389 -0.406267)
			(end -0.787389 0.406267)
			(stroke
				(width 0.1524)
				(type default)
			)
			(layer "B.SilkS")
		)
		(fp_line
			(start -0.787389 0.406267)
			(end 0.787389 0.406267)
			(stroke
				(width 0.1524)
				(type default)
			)
			(layer "B.SilkS")
		)
		(fp_line
			(start 0.787389 -0.406267)
			(end -0.787389 -0.406267)
			(stroke
				(width 0.1524)
				(type default)
			)
			(layer "B.SilkS")
		)
		(fp_line
			(start 0.787389 0.406267)
			(end 0.787389 -0.406267)
			(stroke
				(width 0.1524)
				(type default)
			)
			(layer "B.SilkS")
		)
		(fp_line
			(start -0.679446 -0.30479)
			(end -0.679446 0.30479)
			(stroke
				(width 0.1)
				(type default)
			)
			(layer "B.Fab")
		)
		(fp_line
			(start -0.120515 -0.30479)
			(end -0.679446 -0.30479)
			(stroke
				(width 0.1)
				(type default)
			)
			(layer "B.Fab")
		)
		(fp_line
			(start -0.120695 -0.279466)
			(end -0.120515 -0.30479)
			(stroke
				(width 0.1)
				(type default)
			)
			(layer "B.Fab")
		)
		(fp_line
			(start -0.679446 0.30479)
			(end -0.120515 0.30479)
			(stroke
				(width 0.1)
				(type default)
			)
			(layer "B.Fab")
		)
		(fp_line
			(start 0.120695 -0.304969)
			(end 0.120695 -0.279466)
			(stroke
				(width 0.1)
				(type default)
			)
			(layer "B.Fab")
		)
		(fp_line
			(start 0.120695 -0.279466)
			(end -0.120695 -0.279466)
			(stroke
				(width 0.1)
				(type default)
			)
			(layer "B.Fab")
		)
		(fp_line
			(start -0.120335 0.279466)
			(end 0.120695 0.279466)
			(stroke
				(width 0.1)
				(type default)
			)
			(layer "B.Fab")
		)
		(fp_line
			(start -0.120515 0.30479)
			(end -0.120335 0.279466)
			(stroke
				(width 0.1)
				(type default)
			)
			(layer "B.Fab")
		)
		(fp_line
			(start 0.679446 -0.305149)
			(end 0.120695 -0.304969)
			(stroke
				(width 0.1)
				(type default)
			)
			(layer "B.Fab")
		)
		(fp_line
			(start 0.120695 0.279466)
			(end 0.120515 0.30479)
			(stroke
				(width 0.1)
				(type default)
			)
			(layer "B.Fab")
		)
		(fp_line
			(start 0.120515 0.30479)
			(end 0.679446 0.30479)
			(stroke
				(width 0.1)
				(type default)
			)
			(layer "B.Fab")
		)
		(fp_line
			(start 0.679446 0.30479)
			(end 0.679446 -0.305149)
			(stroke
				(width 0.1)
				(type default)
			)
			(layer "B.Fab")
		)
		(pad "1" smd circle
			(at 0.40005 0 225)
			(size 0 0)
			(layers "B.Cu" "B.Mask" "B.Paste")
			(net "PVCCA_AUX_PLD")
		)
		(pad "2" smd circle
			(at -0.40005 0 225)
			(size 0 0)
			(layers "B.Cu" "B.Mask" "B.Paste")
			(net "GND")
		)
	)
	(footprint ""
		(layer "B.Cu")
		(at 71.034656 -53.215794)
		(property "Reference" "C6"
			(at 0 0 0)
			(layer "B.SilkS")
			(hide yes)
			(effects
				(font
					(size 1.27 1.27)
				)
				(justify mirror)
			)
		)
		(property "Value" ""
			(at 0 0 0)
			(layer "B.Fab")
			(effects
				(font
					(size 1.27 1.27)
				)
				(justify mirror)
			)
		)
		(duplicate_pad_numbers_are_jumpers no)
		(fp_line
			(start -0.7874 -0.4064)
			(end -0.7874 0.4064)
			(stroke
				(width 0.1524)
				(type default)
			)
			(layer "B.SilkS")
		)
		(fp_line
			(start -0.7874 0.4064)
			(end 0.7874 0.4064)
			(stroke
				(width 0.1524)
				(type default)
			)
			(layer "B.SilkS")
		)
		(fp_line
			(start 0.7874 -0.4064)
			(end -0.7874 -0.4064)
			(stroke
				(width 0.1524)
				(type default)
			)
			(layer "B.SilkS")
		)
		(fp_line
			(start 0.7874 0.4064)
			(end 0.7874 -0.4064)
			(stroke
				(width 0.1524)
				(type default)
			)
			(layer "B.SilkS")
		)
		(fp_line
			(start -0.67945 -0.3048)
			(end -0.67945 0.3048)
			(stroke
				(width 0.1)
				(type default)
			)
			(layer "B.Fab")
		)
		(fp_line
			(start -0.67945 0.3048)
			(end -0.120396 0.3048)
			(stroke
				(width 0.1)
				(type default)
			)
			(layer "B.Fab")
		)
		(fp_line
			(start -0.12065 -0.3048)
			(end -0.67945 -0.3048)
			(stroke
				(width 0.1)
				(type default)
			)
			(layer "B.Fab")
		)
		(fp_line
			(start -0.12065 -0.2794)
			(end -0.12065 -0.3048)
			(stroke
				(width 0.1)
				(type default)
			)
			(layer "B.Fab")
		)
		(fp_line
			(start -0.120396 0.2794)
			(end 0.12065 0.2794)
			(stroke
				(width 0.1)
				(type default)
			)
			(layer "B.Fab")
		)
		(fp_line
			(start -0.120396 0.3048)
			(end -0.120396 0.2794)
			(stroke
				(width 0.1)
				(type default)
			)
			(layer "B.Fab")
		)
		(fp_line
			(start 0.12065 -0.305054)
			(end 0.12065 -0.2794)
			(stroke
				(width 0.1)
				(type default)
			)
			(layer "B.Fab")
		)
		(fp_line
			(start 0.12065 -0.2794)
			(end -0.12065 -0.2794)
			(stroke
				(width 0.1)
				(type default)
			)
			(layer "B.Fab")
		)
		(fp_line
			(start 0.12065 0.2794)
			(end 0.12065 0.3048)
			(stroke
				(width 0.1)
				(type default)
			)
			(layer "B.Fab")
		)
		(fp_line
			(start 0.12065 0.3048)
			(end 0.67945 0.3048)
			(stroke
				(width 0.1)
				(type default)
			)
			(layer "B.Fab")
		)
		(fp_line
			(start 0.67945 -0.305054)
			(end 0.12065 -0.305054)
			(stroke
				(width 0.1)
				(type default)
			)
			(layer "B.Fab")
		)
		(fp_line
			(start 0.67945 0.3048)
			(end 0.67945 -0.305054)
			(stroke
				(width 0.1)
				(type default)
			)
			(layer "B.Fab")
		)
		(pad "1" smd circle
			(at 0.40005 0 180)
			(size 0 0)
			(layers "B.Cu" "B.Mask" "B.Paste")
			(net "P2V5_AUX")
		)
		(pad "2" smd circle
			(at -0.40005 0 180)
			(size 0 0)
			(layers "B.Cu" "B.Mask" "B.Paste")
			(net "GND")
		)
	)
)
